(kicad_pcb
	(version 20260206)
	(generator "pcbnew")
	(generator_version "10.0")
	(general
		(thickness 1.6)
		(legacy_teardrops no)
	)
	(paper "A4")
	(title_block
		(title "Bryce Canyon_SCC_16316-1_OCP.brd")
		(comment 1 "Bryce Canyon / footprints 1464-1471 of 1561")
	)
	(layers
		(0 "F.Cu" signal "TOP")
		(4 "In1.Cu" signal "L2GND")
		(6 "In2.Cu" signal "L3")
		(8 "In3.Cu" signal "L4VCC")
		(10 "In4.Cu" signal "L5VCC")
		(12 "In5.Cu" signal "L6")
		(14 "In6.Cu" signal "L7GND")
		(2 "B.Cu" signal "BOTTOM")
		(9 "F.Adhes" user "F.Adhesive")
		(11 "B.Adhes" user "B.Adhesive")
		(13 "F.Paste" user "Package Geometry/Pastemask Top")
		(15 "B.Paste" user "Package Geometry/Pastemask Bottom")
		(5 "F.SilkS" user "Ref Des/Silkscreen Top")
		(7 "B.SilkS" user "Ref Des/Silkscreen Bottom")
		(1 "F.Mask" user "Board Geometry/Soldermask Top")
		(3 "B.Mask" user "Board Geometry/Soldermask Bottom")
		(17 "Dwgs.User" user "User.Drawings")
		(19 "Cmts.User" user "User.Comments")
		(21 "Eco1.User" user "User.Eco1")
		(23 "Eco2.User" user "User.Eco2")
		(25 "Edge.Cuts" user "Board Geometry/Outline")
		(27 "Margin" user)
		(31 "F.CrtYd" user "Package Geometry/Place Bound Top")
		(29 "B.CrtYd" user "Package Geometry/Place Bound Bottom")
		(35 "F.Fab" user "Ref Des/Assembly Top")
		(33 "B.Fab" user "Ref Des/Assembly Bottom")
	)
	(footprint ""
		(layer "B.Cu")
		(at 113.6142 -87.0204)
		(property "Reference" "R405"
			(at 0 0 0)
			(layer "B.SilkS")
			(hide yes)
			(effects
				(font
					(size 1.27 1.27)
				)
				(justify mirror)
			)
		)
		(property "Value" "4K7R2F-GP"
			(at -0.064008 -3.993896 0)
			(unlocked yes)
			(layer "B.Fab")
			(hide yes)
			(effects
				(font
					(size 1.016 1.016)
					(thickness 0.1524)
				)
				(justify mirror)
			)
		)
		(property "Device Type" "R402H16"
			(at -0.064008 -5.517896 0)
			(unlocked yes)
			(layer "B.Fab")
			(hide yes)
			(effects
				(font
					(size 1.016 1.016)
					(thickness 0.1524)
				)
				(justify mirror)
			)
		)
		(duplicate_pad_numbers_are_jumpers no)
		(fp_line
			(start -0.508 -0.9398)
			(end 0.508 -0.9398)
			(stroke
				(width 0.1524)
				(type default)
			)
			(layer "B.SilkS")
		)
		(fp_line
			(start 0.508 -0.9398)
			(end 0.508 0.9398)
			(stroke
				(width 0.1524)
				(type default)
			)
			(layer "B.SilkS")
		)
		(fp_rect
			(start 0.508 0.9398)
			(end -0.508 -0.9398)
			(stroke
				(width 0)
				(type default)
			)
			(fill no)
			(layer "B.CrtYd")
		)
		(fp_rect
			(start 0.508 0.9398)
			(end -0.508 -0.9398)
			(stroke
				(width 0)
				(type default)
			)
			(fill no)
			(layer "B.Fab")
		)
		(pad "1" smd custom
			(at 0 -0.4445 180)
			(size 0.1397 0.1397)
			(layers "B.Cu" "B.Mask" "B.Paste")
			(net "P1V8_E")
			(options
				(clearance outline)
				(anchor circle)
			)
			(primitives
				(gr_poly
					(pts
						(arc
							(start -0.1778 0.2794)
							(mid -0.249642 0.249642)
							(end -0.2794 0.1778)
						)
						(arc
							(start -0.2794 -0.1778)
							(mid -0.249642 -0.249642)
							(end -0.1778 -0.2794)
						)
						(arc
							(start 0.1778 -0.2794)
							(mid 0.249642 -0.249642)
							(end 0.2794 -0.1778)
						)
						(arc
							(start 0.2794 0.1778)
							(mid 0.249642 0.249642)
							(end 0.1778 0.2794)
						)
					)
					(width 0)
					(fill yes)
				)
			)
		)
		(pad "2" smd custom
			(at 0 0.4445 180)
			(size 0.1397 0.1397)
			(layers "B.Cu" "B.Mask" "B.Paste")
			(net "EXP_XM_ADDR_19")
			(options
				(clearance outline)
				(anchor circle)
			)
			(primitives
				(gr_poly
					(pts
						(arc
							(start -0.1778 0.2794)
							(mid -0.249642 0.249642)
							(end -0.2794 0.1778)
						)
						(arc
							(start -0.2794 -0.1778)
							(mid -0.249642 -0.249642)
							(end -0.1778 -0.2794)
						)
						(arc
							(start 0.1778 -0.2794)
							(mid 0.249642 -0.249642)
							(end 0.2794 -0.1778)
						)
						(arc
							(start 0.2794 0.1778)
							(mid 0.249642 0.249642)
							(end 0.1778 0.2794)
						)
					)
					(width 0)
					(fill yes)
				)
			)
		)
	)
	(footprint ""
		(layer "B.Cu")
		(at 172.995336 -51.19243 -90)
		(property "Reference" "R232"
			(at 0 0 90)
			(layer "B.SilkS")
			(hide yes)
			(effects
				(font
					(size 1.27 1.27)
				)
				(justify mirror)
			)
		)
		(property "Value" "10KR2F-2-GP"
			(at -0.064008 -3.993896 270)
			(unlocked yes)
			(layer "B.Fab")
			(hide yes)
			(effects
				(font
					(size 1.016 1.016)
					(thickness 0.1524)
				)
				(justify mirror)
			)
		)
		(property "Device Type" "R402H16"
			(at -0.064008 -5.517896 270)
			(unlocked yes)
			(layer "B.Fab")
			(hide yes)
			(effects
				(font
					(size 1.016 1.016)
					(thickness 0.1524)
				)
				(justify mirror)
			)
		)
		(duplicate_pad_numbers_are_jumpers no)
		(fp_line
			(start -0.508 -0.9398)
			(end 0.508 -0.9398)
			(stroke
				(width 0.1524)
				(type default)
			)
			(layer "B.SilkS")
		)
		(fp_line
			(start 0.508 -0.9398)
			(end 0.508 0.9398)
			(stroke
				(width 0.1524)
				(type default)
			)
			(layer "B.SilkS")
		)
		(fp_rect
			(start 0.508 0.9398)
			(end -0.508 -0.9398)
			(stroke
				(width 0)
				(type default)
			)
			(fill no)
			(layer "B.CrtYd")
		)
		(fp_rect
			(start 0.508 0.9398)
			(end -0.508 -0.9398)
			(stroke
				(width 0)
				(type default)
			)
			(fill no)
			(layer "B.Fab")
		)
		(pad "1" smd custom
			(at 0 -0.4445 90)
			(size 0.1397 0.1397)
			(layers "B.Cu" "B.Mask" "B.Paste")
			(net "P1V8_C")
			(options
				(clearance outline)
				(anchor circle)
			)
			(primitives
				(gr_poly
					(pts
						(arc
							(start -0.1778 0.2794)
							(mid -0.249642 0.249642)
							(end -0.2794 0.1778)
						)
						(arc
							(start -0.2794 -0.1778)
							(mid -0.249642 -0.249642)
							(end -0.1778 -0.2794)
						)
						(arc
							(start 0.1778 -0.2794)
							(mid 0.249642 -0.249642)
							(end 0.2794 -0.1778)
						)
						(arc
							(start 0.2794 0.1778)
							(mid 0.249642 0.249642)
							(end 0.1778 0.2794)
						)
					)
					(width 0)
					(fill yes)
				)
			)
		)
		(pad "2" smd custom
			(at 0 0.4445 90)
			(size 0.1397 0.1397)
			(layers "B.Cu" "B.Mask" "B.Paste")
			(net "AVSO_IDDTN18")
			(options
				(clearance outline)
				(anchor circle)
			)
			(primitives
				(gr_poly
					(pts
						(arc
							(start -0.1778 0.2794)
							(mid -0.249642 0.249642)
							(end -0.2794 0.1778)
						)
						(arc
							(start -0.2794 -0.1778)
							(mid -0.249642 -0.249642)
							(end -0.1778 -0.2794)
						)
						(arc
							(start 0.1778 -0.2794)
							(mid 0.249642 -0.249642)
							(end 0.2794 -0.1778)
						)
						(arc
							(start 0.2794 0.1778)
							(mid 0.249642 0.249642)
							(end 0.1778 0.2794)
						)
					)
					(width 0)
					(fill yes)
				)
			)
		)
	)
	(footprint ""
		(layer "B.Cu")
		(at 115.834414 -90.51417 -90)
		(property "Reference" "R37"
			(at 0 0 90)
			(layer "B.SilkS")
			(hide yes)
			(effects
				(font
					(size 1.27 1.27)
				)
				(justify mirror)
			)
		)
		(property "Value" "4K7R2F-GP"
			(at -0.064008 -3.993896 270)
			(unlocked yes)
			(layer "B.Fab")
			(hide yes)
			(effects
				(font
					(size 1.016 1.016)
					(thickness 0.1524)
				)
				(justify mirror)
			)
		)
		(property "Device Type" "R402H16"
			(at -0.064008 -5.517896 270)
			(unlocked yes)
			(layer "B.Fab")
			(hide yes)
			(effects
				(font
					(size 1.016 1.016)
					(thickness 0.1524)
				)
				(justify mirror)
			)
		)
		(duplicate_pad_numbers_are_jumpers no)
		(fp_line
			(start -0.508 -0.9398)
			(end 0.508 -0.9398)
			(stroke
				(width 0.1524)
				(type default)
			)
			(layer "B.SilkS")
		)
		(fp_line
			(start 0.508 -0.9398)
			(end 0.508 0.9398)
			(stroke
				(width 0.1524)
				(type default)
			)
			(layer "B.SilkS")
		)
		(fp_rect
			(start 0.508 0.9398)
			(end -0.508 -0.9398)
			(stroke
				(width 0)
				(type default)
			)
			(fill no)
			(layer "B.CrtYd")
		)
		(fp_rect
			(start 0.508 0.9398)
			(end -0.508 -0.9398)
			(stroke
				(width 0)
				(type default)
			)
			(fill no)
			(layer "B.Fab")
		)
		(pad "1" smd custom
			(at 0 -0.4445 90)
			(size 0.1397 0.1397)
			(layers "B.Cu" "B.Mask" "B.Paste")
			(net "P1V8_E")
			(options
				(clearance outline)
				(anchor circle)
			)
			(primitives
				(gr_poly
					(pts
						(arc
							(start -0.1778 0.2794)
							(mid -0.249642 0.249642)
							(end -0.2794 0.1778)
						)
						(arc
							(start -0.2794 -0.1778)
							(mid -0.249642 -0.249642)
							(end -0.1778 -0.2794)
						)
						(arc
							(start 0.1778 -0.2794)
							(mid 0.249642 -0.249642)
							(end 0.2794 -0.1778)
						)
						(arc
							(start 0.2794 0.1778)
							(mid 0.249642 0.249642)
							(end 0.1778 0.2794)
						)
					)
					(width 0)
					(fill yes)
				)
			)
		)
		(pad "2" smd custom
			(at 0 0.4445 90)
			(size 0.1397 0.1397)
			(layers "B.Cu" "B.Mask" "B.Paste")
			(net "EXP_GPIO14")
			(options
				(clearance outline)
				(anchor circle)
			)
			(primitives
				(gr_poly
					(pts
						(arc
							(start -0.1778 0.2794)
							(mid -0.249642 0.249642)
							(end -0.2794 0.1778)
						)
						(arc
							(start -0.2794 -0.1778)
							(mid -0.249642 -0.249642)
							(end -0.1778 -0.2794)
						)
						(arc
							(start 0.1778 -0.2794)
							(mid 0.249642 -0.249642)
							(end 0.2794 -0.1778)
						)
						(arc
							(start 0.2794 0.1778)
							(mid 0.249642 0.249642)
							(end 0.1778 0.2794)
						)
					)
					(width 0)
					(fill yes)
				)
			)
		)
	)
	(footprint ""
		(layer "B.Cu")
		(at 134.493254 -65.066418 -90)
		(property "Reference" "C21"
			(at 0 0 90)
			(layer "B.SilkS")
			(hide yes)
			(effects
				(font
					(size 1.27 1.27)
				)
				(justify mirror)
			)
		)
		(property "Value" "SCD01U16V1KX-GP"
			(at 2.8321 -1.7399 270)
			(unlocked yes)
			(layer "B.Fab")
			(hide yes)
			(effects
				(font
					(size 1.016 1.016)
					(thickness 0.1524)
				)
				(justify mirror)
			)
		)
		(property "Device Type" "C0201H13"
			(at 2.8321 -3.2639 270)
			(unlocked yes)
			(layer "B.Fab")
			(hide yes)
			(effects
				(font
					(size 1.016 1.016)
					(thickness 0.1524)
				)
				(justify mirror)
			)
		)
		(duplicate_pad_numbers_are_jumpers no)
		(fp_rect
			(start 0.2794 0.6477)
			(end -0.2794 -0.6477)
			(stroke
				(width 0)
				(type default)
			)
			(fill no)
			(layer "B.CrtYd")
		)
		(fp_rect
			(start 0.2794 0.6477)
			(end -0.2794 -0.6477)
			(stroke
				(width 0)
				(type default)
			)
			(fill no)
			(layer "B.Fab")
		)
		(pad "1" smd custom
			(at 0 -0.2794 90)
			(size 0.0762 0.0762)
			(layers "B.Cu" "B.Mask" "B.Paste")
			(net "PHY_DPB_TO_SCC_1_DP")
			(options
				(clearance outline)
				(anchor circle)
			)
			(primitives
				(gr_poly
					(pts
						(arc
							(start 0.1524 0.127)
							(mid 0.137521 0.162921)
							(end 0.1016 0.1778)
						)
						(arc
							(start -0.1016 0.1778)
							(mid -0.137521 0.162921)
							(end -0.1524 0.127)
						)
						(arc
							(start -0.1524 -0.127)
							(mid -0.137521 -0.162921)
							(end -0.1016 -0.1778)
						)
						(arc
							(start 0.1016 -0.1778)
							(mid 0.137521 -0.162921)
							(end 0.1524 -0.127)
						)
					)
					(width 0)
					(fill yes)
				)
			)
		)
		(pad "2" smd custom
			(at 0 0.2794 90)
			(size 0.0762 0.0762)
			(layers "B.Cu" "B.Mask" "B.Paste")
			(net "PHY_DPB_TO_SCC_C_1_DP")
			(options
				(clearance outline)
				(anchor circle)
			)
			(primitives
				(gr_poly
					(pts
						(arc
							(start 0.1524 0.127)
							(mid 0.137521 0.162921)
							(end 0.1016 0.1778)
						)
						(arc
							(start -0.1016 0.1778)
							(mid -0.137521 0.162921)
							(end -0.1524 0.127)
						)
						(arc
							(start -0.1524 -0.127)
							(mid -0.137521 -0.162921)
							(end -0.1016 -0.1778)
						)
						(arc
							(start 0.1016 -0.1778)
							(mid 0.137521 -0.162921)
							(end 0.1524 -0.127)
						)
					)
					(width 0)
					(fill yes)
				)
			)
		)
	)
	(footprint ""
		(layer "B.Cu")
		(at 114.681 -68.6562)
		(property "Reference" "C166"
			(at 0 0 0)
			(layer "B.SilkS")
			(hide yes)
			(effects
				(font
					(size 1.27 1.27)
				)
				(justify mirror)
			)
		)
		(property "Value" "SCD1U6D3V1KX-GP"
			(at 2.8321 -1.7399 0)
			(unlocked yes)
			(layer "B.Fab")
			(hide yes)
			(effects
				(font
					(size 1.016 1.016)
					(thickness 0.1524)
				)
				(justify mirror)
			)
		)
		(property "Device Type" "C0201H13"
			(at 2.8321 -3.2639 0)
			(unlocked yes)
			(layer "B.Fab")
			(hide yes)
			(effects
				(font
					(size 1.016 1.016)
					(thickness 0.1524)
				)
				(justify mirror)
			)
		)
		(duplicate_pad_numbers_are_jumpers no)
		(fp_rect
			(start 0.2794 0.6477)
			(end -0.2794 -0.6477)
			(stroke
				(width 0)
				(type default)
			)
			(fill no)
			(layer "B.CrtYd")
		)
		(fp_rect
			(start 0.2794 0.6477)
			(end -0.2794 -0.6477)
			(stroke
				(width 0)
				(type default)
			)
			(fill no)
			(layer "B.Fab")
		)
		(pad "1" smd custom
			(at 0 -0.2794 180)
			(size 0.0762 0.0762)
			(layers "B.Cu" "B.Mask" "B.Paste")
			(net "P0V9")
			(options
				(clearance outline)
				(anchor circle)
			)
			(primitives
				(gr_poly
					(pts
						(arc
							(start 0.1524 0.127)
							(mid 0.137521 0.162921)
							(end 0.1016 0.1778)
						)
						(arc
							(start -0.1016 0.1778)
							(mid -0.137521 0.162921)
							(end -0.1524 0.127)
						)
						(arc
							(start -0.1524 -0.127)
							(mid -0.137521 -0.162921)
							(end -0.1016 -0.1778)
						)
						(arc
							(start 0.1016 -0.1778)
							(mid 0.137521 -0.162921)
							(end 0.1524 -0.127)
						)
					)
					(width 0)
					(fill yes)
				)
			)
		)
		(pad "2" smd custom
			(at 0 0.2794 180)
			(size 0.0762 0.0762)
			(layers "B.Cu" "B.Mask" "B.Paste")
			(net "GND")
			(options
				(clearance outline)
				(anchor circle)
			)
			(primitives
				(gr_poly
					(pts
						(arc
							(start 0.1524 0.127)
							(mid 0.137521 0.162921)
							(end 0.1016 0.1778)
						)
						(arc
							(start -0.1016 0.1778)
							(mid -0.137521 0.162921)
							(end -0.1524 0.127)
						)
						(arc
							(start -0.1524 -0.127)
							(mid -0.137521 -0.162921)
							(end -0.1016 -0.1778)
						)
						(arc
							(start 0.1016 -0.1778)
							(mid 0.137521 -0.162921)
							(end 0.1524 -0.127)
						)
					)
					(width 0)
					(fill yes)
				)
			)
		)
	)
	(footprint ""
		(layer "B.Cu")
		(at 116.5098 -75.9968 180)
		(property "Reference" "C138"
			(at 0 0 0)
			(layer "B.SilkS")
			(hide yes)
			(effects
				(font
					(size 1.27 1.27)
				)
				(justify mirror)
			)
		)
		(property "Value" "SCD1U6D3V1KX-GP"
			(at 2.8321 -1.7399 180)
			(unlocked yes)
			(layer "B.Fab")
			(hide yes)
			(effects
				(font
					(size 1.016 1.016)
					(thickness 0.1524)
				)
				(justify mirror)
			)
		)
		(property "Device Type" "C0201H13"
			(at 2.8321 -3.2639 180)
			(unlocked yes)
			(layer "B.Fab")
			(hide yes)
			(effects
				(font
					(size 1.016 1.016)
					(thickness 0.1524)
				)
				(justify mirror)
			)
		)
		(duplicate_pad_numbers_are_jumpers no)
		(fp_rect
			(start 0.2794 0.6477)
			(end -0.2794 -0.6477)
			(stroke
				(width 0)
				(type default)
			)
			(fill no)
			(layer "B.CrtYd")
		)
		(fp_rect
			(start 0.2794 0.6477)
			(end -0.2794 -0.6477)
			(stroke
				(width 0)
				(type default)
			)
			(fill no)
			(layer "B.Fab")
		)
		(pad "1" smd custom
			(at 0 -0.2794)
			(size 0.0762 0.0762)
			(layers "B.Cu" "B.Mask" "B.Paste")
			(net "P1V8_E")
			(options
				(clearance outline)
				(anchor circle)
			)
			(primitives
				(gr_poly
					(pts
						(arc
							(start 0.1524 0.127)
							(mid 0.137521 0.162921)
							(end 0.1016 0.1778)
						)
						(arc
							(start -0.1016 0.1778)
							(mid -0.137521 0.162921)
							(end -0.1524 0.127)
						)
						(arc
							(start -0.1524 -0.127)
							(mid -0.137521 -0.162921)
							(end -0.1016 -0.1778)
						)
						(arc
							(start 0.1016 -0.1778)
							(mid 0.137521 -0.162921)
							(end 0.1524 -0.127)
						)
					)
					(width 0)
					(fill yes)
				)
			)
		)
		(pad "2" smd custom
			(at 0 0.2794)
			(size 0.0762 0.0762)
			(layers "B.Cu" "B.Mask" "B.Paste")
			(net "GND")
			(options
				(clearance outline)
				(anchor circle)
			)
			(primitives
				(gr_poly
					(pts
						(arc
							(start 0.1524 0.127)
							(mid 0.137521 0.162921)
							(end 0.1016 0.1778)
						)
						(arc
							(start -0.1016 0.1778)
							(mid -0.137521 0.162921)
							(end -0.1524 0.127)
						)
						(arc
							(start -0.1524 -0.127)
							(mid -0.137521 -0.162921)
							(end -0.1016 -0.1778)
						)
						(arc
							(start 0.1016 -0.1778)
							(mid 0.137521 -0.162921)
							(end 0.1524 -0.127)
						)
					)
					(width 0)
					(fill yes)
				)
			)
		)
	)
	(footprint ""
		(layer "B.Cu")
		(at 123.150376 -91.23553 -90)
		(property "Reference" "R563"
			(at 0 0 90)
			(layer "B.SilkS")
			(hide yes)
			(effects
				(font
					(size 1.27 1.27)
				)
				(justify mirror)
			)
		)
		(property "Value" "10KR2F-2-GP"
			(at -0.064008 -3.993896 270)
			(unlocked yes)
			(layer "B.Fab")
			(hide yes)
			(effects
				(font
					(size 1.016 1.016)
					(thickness 0.1524)
				)
				(justify mirror)
			)
		)
		(property "Device Type" "R402H16"
			(at -0.064008 -5.517896 270)
			(unlocked yes)
			(layer "B.Fab")
			(hide yes)
			(effects
				(font
					(size 1.016 1.016)
					(thickness 0.1524)
				)
				(justify mirror)
			)
		)
		(duplicate_pad_numbers_are_jumpers no)
		(fp_line
			(start -0.508 -0.9398)
			(end 0.508 -0.9398)
			(stroke
				(width 0.1524)
				(type default)
			)
			(layer "B.SilkS")
		)
		(fp_line
			(start 0.508 -0.9398)
			(end 0.508 0.9398)
			(stroke
				(width 0.1524)
				(type default)
			)
			(layer "B.SilkS")
		)
		(fp_rect
			(start 0.508 0.9398)
			(end -0.508 -0.9398)
			(stroke
				(width 0)
				(type default)
			)
			(fill no)
			(layer "B.CrtYd")
		)
		(fp_rect
			(start 0.508 0.9398)
			(end -0.508 -0.9398)
			(stroke
				(width 0)
				(type default)
			)
			(fill no)
			(layer "B.Fab")
		)
		(pad "1" smd custom
			(at 0 -0.4445 90)
			(size 0.1397 0.1397)
			(layers "B.Cu" "B.Mask" "B.Paste")
			(net "BMC_SPARE_0_LS")
			(options
				(clearance outline)
				(anchor circle)
			)
			(primitives
				(gr_poly
					(pts
						(arc
							(start -0.1778 0.2794)
							(mid -0.249642 0.249642)
							(end -0.2794 0.1778)
						)
						(arc
							(start -0.2794 -0.1778)
							(mid -0.249642 -0.249642)
							(end -0.1778 -0.2794)
						)
						(arc
							(start 0.1778 -0.2794)
							(mid 0.249642 -0.249642)
							(end 0.2794 -0.1778)
						)
						(arc
							(start 0.2794 0.1778)
							(mid 0.249642 0.249642)
							(end 0.1778 0.2794)
						)
					)
					(width 0)
					(fill yes)
				)
			)
		)
		(pad "2" smd custom
			(at 0 0.4445 90)
			(size 0.1397 0.1397)
			(layers "B.Cu" "B.Mask" "B.Paste")
			(net "P1V8_E")
			(options
				(clearance outline)
				(anchor circle)
			)
			(primitives
				(gr_poly
					(pts
						(arc
							(start -0.1778 0.2794)
							(mid -0.249642 0.249642)
							(end -0.2794 0.1778)
						)
						(arc
							(start -0.2794 -0.1778)
							(mid -0.249642 -0.249642)
							(end -0.1778 -0.2794)
						)
						(arc
							(start 0.1778 -0.2794)
							(mid 0.249642 -0.249642)
							(end 0.2794 -0.1778)
						)
						(arc
							(start 0.2794 0.1778)
							(mid 0.249642 0.249642)
							(end 0.1778 0.2794)
						)
					)
					(width 0)
					(fill yes)
				)
			)
		)
	)
	(footprint ""
		(layer "B.Cu")
		(at 188.6458 -26.1874 90)
		(property "Reference" "TP65"
			(at 0 0 90)
			(layer "B.SilkS")
			(hide yes)
			(effects
				(font
					(size 1.27 1.27)
				)
				(justify mirror)
			)
		)
		(property "Value" "TPAD28-2-GP"
			(at 0.0127 -1.6637 90)
			(unlocked yes)
			(layer "B.Fab")
			(hide yes)
			(effects
				(font
					(size 1.016 1.016)
					(thickness 0.1524)
				)
				(justify mirror)
			)
		)
		(property "Device Type" "TPAD28"
			(at 0.0127 -3.1877 90)
			(unlocked yes)
			(layer "B.Fab")
			(hide yes)
			(effects
				(font
					(size 1.016 1.016)
					(thickness 0.1524)
				)
				(justify mirror)
			)
		)
		(duplicate_pad_numbers_are_jumpers no)
		(fp_poly
			(pts
				(arc
					(start 0 0.3556)
					(mid 0 -0.3556)
					(end 0 0.3556)
				)
			)
			(stroke
				(width 0)
				(type default)
			)
			(fill no)
			(layer "B.CrtYd")
		)
		(fp_poly
			(pts
				(arc
					(start 0 0.6096)
					(mid 0 -0.6096)
					(end 0 0.6096)
				)
			)
			(stroke
				(width 0)
				(type default)
			)
			(fill no)
			(layer "B.Fab")
		)
		(pad "1" smd circle
			(at 0 0 270)
			(size 0.7112 0.7112)
			(layers "B.Cu" "B.Mask" "B.Paste")
			(net "IOC_GPIO_12")
		)
	)
)
